FILE_TYPE = CONNECTIVITY;
{Allegro Design Entry HDL 16.6-p007 (v16-6-112F) 10/10/2012}
"PAGE_NUMBER" = 52;
0"NC";
1"M_E_DQS_DN<17:0>";
2"M_E_DQS_DP<17:0>";
3"M_E_MA<17:0>";
4"M_E_DQ<63:0>";
5"M_E_BA<1:0>";
6"M_E_BG<1:0>";
7"M_E_CLK_DN<3:0>";
8"M_E_CLK_DP<3:0>";
9"M_E_CS_N<7:0>";
10"M_E_CKE<3:0>";
11"M_E_ODT<3:0>";
12"M_E_ECC<7:0>";
13"GND\g";
14"GND\g";
15"GND\g";
16"P12V_NVDIMM_DEF\g";
17"GND\g";
18"PVPP_DEF\g";
19"PVDDQ_DEF\g";
20"PVTT_DEF\g";
21"PVPP_DEF\g";
22"M_E_VREF";
23"M_E_DQS_DN<0>";
24"TP_CH_E_DIMM_E1_RFU_2";
25"TP_CH_E_DIMM_E1_RFU_0";
26"TP_CH_E_DIMM_E1_RFU_1";
27"M_E_ALERT_N";
28"M_E_ACT_N";
29"FM_ADR_COMPLETE_DEF_N";
30"SMB_DDR_DEF_VPP_SDA";
31"SMB_DDR_DEF_VPP_SCL";
32"M_E_DQ<1>";
33"M_E_DQ<0>";
34"M_E_DQ<2>";
35"M_E_DQ<3>";
36"M_E_DQ<8>";
37"M_E_DQ<7>";
38"M_E_DQ<6>";
39"M_E_DQ<4>";
40"M_E_DQ<5>";
41"M_E_DQ<13>";
42"M_E_DQ<12>";
43"M_E_DQ<11>";
44"M_E_DQ<10>";
45"M_E_DQ<9>";
46"M_DEF_RST_N";
47"FM_DIMM_EVENT_COD_N";
48"M_E_PAR";
49"M_E_ECC<6>";
50"M_E_ECC<5>";
51"M_E_ECC<4>";
52"M_E_ECC<3>";
53"M_E_ECC<2>";
54"M_E_ECC<1>";
55"M_E_ECC<0>";
56"M_E_ECC<7>";
57"M_E_ODT<2>";
58"M_E_CS_N<7>";
59"M_E_CS_N<6>";
60"M_E_CS_N<5>";
61"M_E_CKE<3>";
62"M_E_ODT<3>";
63"M_E_CKE<2>";
64"M_E_CS_N<4>";
65"M_E_C<2>";
66"M_E_CLK_DP<2>";
67"M_E_CLK_DP<3>";
68"M_E_CLK_DN<3>";
69"M_E_CLK_DN<2>";
70"M_E_BA<1>";
71"M_E_BG<0>";
72"M_E_BG<1>";
73"M_E_BA<0>";
74"M_E_MA<0>";
75"M_E_MA<1>";
76"M_E_MA<3>";
77"M_E_MA<4>";
78"M_E_MA<5>";
79"M_E_MA<6>";
80"M_E_MA<7>";
81"M_E_MA<8>";
82"M_E_MA<2>";
83"M_E_DQ<19>";
84"M_E_DQ<18>";
85"M_E_DQ<16>";
86"M_E_DQ<14>";
87"M_E_DQ<15>";
88"M_E_DQ<17>";
89"M_E_DQ<24>";
90"M_E_DQ<23>";
91"M_E_DQ<22>";
92"M_E_DQ<21>";
93"M_E_DQ<20>";
94"M_E_DQ<29>";
95"M_E_DQ<28>";
96"M_E_DQ<25>";
97"M_E_DQ<27>";
98"M_E_DQ<26>";
99"M_E_DQ<34>";
100"M_E_DQ<33>";
101"M_E_DQ<32>";
102"M_E_DQ<31>";
103"M_E_DQ<30>";
104"M_E_DQ<39>";
105"M_E_DQ<37>";
106"M_E_DQ<35>";
107"M_E_DQ<36>";
108"M_E_DQ<38>";
109"M_E_DQ<44>";
110"M_E_DQ<43>";
111"M_E_DQ<42>";
112"M_E_DQ<41>";
113"M_E_DQ<40>";
114"M_E_DQ<46>";
115"M_E_DQ<45>";
116"M_E_DQ<49>";
117"M_E_DQ<48>";
118"M_E_DQ<47>";
119"M_E_DQ<54>";
120"M_E_DQ<53>";
121"M_E_DQ<52>";
122"M_E_DQ<51>";
123"M_E_DQ<50>";
124"M_E_MA<12>";
125"M_E_MA<13>";
126"M_E_MA<17>";
127"M_E_MA<9>";
128"M_E_MA<10>";
129"M_E_MA<11>";
130"M_E_MA<14>";
131"M_E_MA<15>";
132"M_E_MA<16>";
133"M_E_DQ<60>";
134"M_E_DQ<59>";
135"M_E_DQ<56>";
136"M_E_DQ<55>";
137"M_E_DQ<57>";
138"M_E_DQ<58>";
139"M_E_DQ<63>";
140"M_E_DQ<62>";
141"M_E_DQ<61>";
142"M_E_DQS_DP<0>";
143"M_E_DQS_DP<1>";
144"M_E_DQS_DP<2>";
145"M_E_DQS_DP<3>";
146"M_E_DQS_DP<4>";
147"M_E_DQS_DP<5>";
148"M_E_DQS_DN<1>";
149"M_E_DQS_DN<2>";
150"M_E_DQS_DN<3>";
151"M_E_DQS_DN<4>";
152"M_E_DQS_DN<5>";
153"M_E_DQS_DP<6>";
154"M_E_DQS_DP<7>";
155"M_E_DQS_DP<10>";
156"M_E_DQS_DP<8>";
157"M_E_DQS_DP<9>";
158"M_E_DQS_DN<10>";
159"M_E_DQS_DN<6>";
160"M_E_DQS_DN<7>";
161"M_E_DQS_DN<8>";
162"M_E_DQS_DN<9>";
163"M_E_DQS_DP<11>";
164"M_E_DQS_DP<12>";
165"M_E_DQS_DP<13>";
166"M_E_DQS_DP<14>";
167"M_E_DQS_DP<15>";
168"M_E_DQS_DN<11>";
169"M_E_DQS_DN<12>";
170"M_E_DQS_DN<13>";
171"M_E_DQS_DN<14>";
172"M_E_DQS_DN<15>";
173"M_E_DQS_DN<16>";
174"M_E_DQS_DP<16>";
175"M_E_DQS_DP<17>";
176"M_E_DQS_DN<17>";
%"GND"
"1","(-3575,1500)","2","mstr_symbols","I1";
;
HDL_POWER"GND"
BODY_TYPE"PLUMBING"
SIZE"1B"
CDS_LIB"mstr_symbols"
VOLTAGE"0";
"A\NAC"13;
%"SCONN288_H44441003"
"2","(1625,3900)","0","mstr_sconn","I100";
;
CDS_SEC"2"
ROOM"DDR4_CH_E"
CDS_LOCATION"J6L2"
SEC"2"
SEC_TYPE"PIP"
CDS_LIB"mstr_sconn"
BOM_COST"MEM"
PACK_TYPE"PIP"
MATERIAL"SCONN"
PART_NUMBER"H44441-003"
LOCATION"J6L2";
"DQS0N"
$PN"152"23;
"DQS0P"
$PN"153"142;
"DQS10N"
$PN"19"158;
"DQS10P"
$PN"18"155;
"DQS11N"
$PN"30"168;
"DQS11P"
$PN"29"163;
"DQS12N"
$PN"41"169;
"DQS12P"
$PN"40"164;
"DQS13N"
$PN"100"170;
"DQS13P"
$PN"99"165;
"DQS14N"
$PN"111"171;
"DQS14P"
$PN"110"166;
"DQS15N"
$PN"122"172;
"DQS15P"
$PN"121"167;
"DQS16N"
$PN"133"173;
"DQS16P"
$PN"132"174;
"DQS17N"
$PN"52"176;
"DQS17P"
$PN"51"175;
"DQS1N"
$PN"163"148;
"DQS1P"
$PN"164"143;
"DQS2N"
$PN"174"149;
"DQS2P"
$PN"175"144;
"DQS3N"
$PN"185"150;
"DQS3P"
$PN"186"145;
"DQS4N"
$PN"244"151;
"DQS4P"
$PN"245"146;
"DQS5N"
$PN"255"152;
"DQS5P"
$PN"256"147;
"DQS6N"
$PN"266"159;
"DQS6P"
$PN"267"153;
"DQS7N"
$PN"277"160;
"DQS7P"
$PN"278"154;
"DQS8N"
$PN"196"161;
"DQS8P"
$PN"197"156;
"DQS9N"
$PN"8"162;
"DQS9P"
$PN"7"157;
%"TAP"
"6","(-1475,3750)","0","mstr_standard","I102";
;
HDL_TAP"TRUE"
BODY_TYPE"PLUMBING"
CDS_LIB"mstr_standard";
"B \NAC \NWC"3;
"S \NAC"
BN"2"82;
%"TAP"
"6","(-1475,3700)","0","mstr_standard","I103";
;
HDL_TAP"TRUE"
BODY_TYPE"PLUMBING"
CDS_LIB"mstr_standard";
"B \NAC \NWC"3;
"S \NAC"
BN"1"75;
%"TAP"
"6","(-1475,3800)","0","mstr_standard","I104";
;
HDL_TAP"TRUE"
BODY_TYPE"PLUMBING"
CDS_LIB"mstr_standard";
"B \NAC \NWC"3;
"S \NAC"
BN"3"76;
%"TAP"
"6","(-1475,3900)","0","mstr_standard","I105";
;
HDL_TAP"TRUE"
BODY_TYPE"PLUMBING"
CDS_LIB"mstr_standard";
"B \NAC \NWC"3;
"S \NAC"
BN"5"78;
%"TAP"
"6","(-1475,3850)","0","mstr_standard","I106";
;
HDL_TAP"TRUE"
BODY_TYPE"PLUMBING"
CDS_LIB"mstr_standard";
"B \NAC \NWC"3;
"S \NAC"
BN"4"77;
%"TAP"
"6","(-1475,3950)","0","mstr_standard","I107";
;
HDL_TAP"TRUE"
BODY_TYPE"PLUMBING"
CDS_LIB"mstr_standard";
"B \NAC \NWC"3;
"S \NAC"
BN"6"79;
%"TAP"
"6","(-1475,4050)","0","mstr_standard","I108";
;
HDL_TAP"TRUE"
BODY_TYPE"PLUMBING"
CDS_LIB"mstr_standard";
"B \NAC \NWC"3;
"S \NAC"
BN"8"81;
%"TAP"
"6","(-1475,4000)","0","mstr_standard","I109";
;
HDL_TAP"TRUE"
BODY_TYPE"PLUMBING"
CDS_LIB"mstr_standard";
"B \NAC \NWC"3;
"S \NAC"
BN"7"80;
%"TAP"
"6","(-1475,4150)","0","mstr_standard","I110";
;
HDL_TAP"TRUE"
BODY_TYPE"PLUMBING"
CDS_LIB"mstr_standard";
"B \NAC \NWC"3;
"S \NAC"
BN"10"128;
%"TAP"
"6","(-1475,4100)","0","mstr_standard","I111";
;
HDL_TAP"TRUE"
BODY_TYPE"PLUMBING"
CDS_LIB"mstr_standard";
"B \NAC \NWC"3;
"S \NAC"
BN"9"127;
%"TAP"
"6","(-1475,4200)","0","mstr_standard","I112";
;
HDL_TAP"TRUE"
BODY_TYPE"PLUMBING"
CDS_LIB"mstr_standard";
"B \NAC \NWC"3;
"S \NAC"
BN"11"129;
%"TAP"
"6","(-1475,4300)","0","mstr_standard","I113";
;
HDL_TAP"TRUE"
BODY_TYPE"PLUMBING"
CDS_LIB"mstr_standard";
"B \NAC \NWC"3;
"S \NAC"
BN"13"125;
%"TAP"
"6","(-1475,4250)","0","mstr_standard","I114";
;
HDL_TAP"TRUE"
BODY_TYPE"PLUMBING"
CDS_LIB"mstr_standard";
"B \NAC \NWC"3;
"S \NAC"
BN"12"124;
%"TAP"
"6","(-1475,4400)","0","mstr_standard","I115";
;
HDL_TAP"TRUE"
BODY_TYPE"PLUMBING"
CDS_LIB"mstr_standard";
"B \NAC \NWC"3;
"S \NAC"
BN"15"131;
%"TAP"
"6","(-1475,4350)","0","mstr_standard","I116";
;
HDL_TAP"TRUE"
BODY_TYPE"PLUMBING"
CDS_LIB"mstr_standard";
"B \NAC \NWC"3;
"S \NAC"
BN"14"130;
%"TAP"
"6","(-1475,4450)","0","mstr_standard","I117";
;
HDL_TAP"TRUE"
BODY_TYPE"PLUMBING"
CDS_LIB"mstr_standard";
"B \NAC \NWC"3;
"S \NAC"
BN"16"132;
%"TAP"
"6","(-1475,4500)","0","mstr_standard","I118";
;
HDL_TAP"TRUE"
BODY_TYPE"PLUMBING"
CDS_LIB"mstr_standard";
"B \NAC \NWC"3;
"S \NAC"
BN"17"126;
%"TAP"
"6","(25,3800)","2","mstr_standard","I119";
;
HDL_TAP"TRUE"
BODY_TYPE"PLUMBING"
CDS_LIB"mstr_standard";
"B \NAC \NWC"4;
"S \NAC"
BN"49"116;
%"SCONN288_H44441003"
"1","(-725,2850)","0","mstr_sconn","I12";
;
CDS_SEC"1"
ROOM"DDR4_CH_E"
CDS_LOCATION"J6L2"
SEC"1"
SEC_TYPE"PIP"
CDS_LIB"mstr_sconn"
BOM_COST"MEM"
PACK_TYPE"PIP"
MATERIAL"SCONN"
PART_NUMBER"H44441-003"
LOCATION"J6L2";
"DQ<63>"
$PN"280"139;
"BA<1>"
$PN"224"70;
"CK1N"
$PN"219"68;
"CK0P"
$PN"74"66;
"S3_N_C<1>"
$PN"237"58;
"S2_N_C<0>"
$PN"93"59;
"S1_N"
$PN"89"60;
"DQ<29>"
$PN"181"94;
"DQ<28>"
$PN"36"95;
"C<2>"
$PN"235"65;
"A0"
$PN"79"74;
"A1"
$PN"72"75;
"A12"
$PN"65"124;
"A13"
$PN"232"125;
"A17"
$PN"234"126;
"A3"
$PN"71"76;
"A4"
$PN"214"77;
"A5"
$PN"213"78;
"A6"
$PN"69"79;
"A7"
$PN"211"80;
"A8"
$PN"68"81;
"A9"
$PN"66"127;
"CB<6>"
$PN"54"49;
"CB<5>"
$PN"192"50;
"CB<4>"
$PN"47"51;
"CB<3>"
$PN"201"52;
"CB<2>"
$PN"56"53;
"CB<1>"
$PN"194"54;
"CB<0>"
$PN"49"55;
"CK0N"
$PN"75"69;
"CKE<1>"
$PN"203"61;
"DQ<62>"
$PN"135"140;
"DQ<61>"
$PN"273"141;
"DQ<60>"
$PN"128"133;
"DQ<59>"
$PN"282"134;
"DQ<56>"
$PN"130"135;
"DQ<55>"
$PN"269"136;
"DQ<46>"
$PN"113"114;
"DQ<45>"
$PN"251"115;
"DQ<44>"
$PN"106"109;
"DQ<43>"
$PN"260"110;
"DQ<42>"
$PN"115"111;
"DQ<41>"
$PN"253"112;
"DQ<40>"
$PN"108"113;
"DQ<39>"
$PN"247"104;
"DQ<37>"
$PN"240"105;
"DQ<34>"
$PN"104"99;
"DQ<33>"
$PN"242"100;
"DQ<32>"
$PN"97"101;
"DQ<31>"
$PN"188"102;
"DQ<30>"
$PN"43"103;
"DQ<25>"
$PN"183"96;
"DQ<24>"
$PN"38"89;
"DQ<23>"
$PN"177"90;
"DQ<22>"
$PN"32"91;
"DQ<21>"
$PN"170"92;
"DQ<20>"
$PN"25"93;
"DQ<19>"
$PN"179"83;
"DQ<18>"
$PN"34"84;
"DQ<16>"
$PN"27"85;
"DQ<14>"
$PN"21"86;
"DQ<13>"
$PN"159"41;
"DQ<12>"
$PN"14"42;
"DQ<11>"
$PN"168"43;
"DQ<10>"
$PN"23"44;
"DQ<9>"
$PN"161"45;
"DQ<8>"
$PN"16"36;
"DQ<7>"
$PN"155"37;
"DQ<6>"
$PN"10"38;
"EVENT_N"
$PN"78"47;
"PAR"
$PN"222"48;
"RESET_N"
$PN"58"46;
"RFU<2>"
$PN"144"24;
"SCL"
$PN"141"31;
"SDA"
$PN"285"30;
"VREFCA"
$PN"146"22;
"CK1P"
$PN"218"67;
"BG<0>"
$PN"63"71;
"BG<1>"
$PN"207"72;
"BA<0>"
$PN"81"73;
"SA<0>"
$PN"139"18;
"VDDSPD"
$PN"284"18;
"SA<2>"
$PN"238"13;
"SA<1>"
$PN"140"18;
"DQ<1>"
$PN"150"32;
"DQ<0>"
$PN"5"33;
"ACT_N"
$PN"62"28;
"ALERT_N"
$PN"208"27;
"A2"
$PN"216"82;
"DQ<35>"
$PN"249"106;
"DQ<36>"
$PN"95"107;
"DQ<38>"
$PN"102"108;
"A10"
$PN"225"128;
"A11"
$PN"210"129;
"A14_WE_N"
$PN"228"130;
"A15_CAS_N"
$PN"86"131;
"A16_RAS_N"
$PN"82"132;
"CB<7>"
$PN"199"56;
"ODT<0>"
$PN"87"57;
"ODT<1>"
$PN"91"62;
"CKE<0>"
$PN"60"63;
"S0_N"
$PN"84"64;
"DQ<27>"
$PN"190"97;
"DQ<26>"
$PN"45"98;
"DQ<15>"
$PN"166"87;
"DQ<17>"
$PN"172"88;
"RFU<0>"
$PN"205"25;
"RFU<1>"
$PN"227"26;
"SAVE_N_NC"
$PN"230"29;
"DQ<57>"
$PN"275"137;
"DQ<58>"
$PN"137"138;
"DQ<54>"
$PN"124"119;
"DQ<53>"
$PN"262"120;
"DQ<52>"
$PN"117"121;
"DQ<51>"
$PN"271"122;
"DQ<50>"
$PN"126"123;
"DQ<49>"
$PN"264"116;
"DQ<48>"
$PN"119"117;
"DQ<47>"
$PN"258"118;
"DQ<2>"
$PN"12"34;
"DQ<3>"
$PN"157"35;
"DQ<4>"
$PN"3"39;
"DQ<5>"
$PN"148"40;
%"TAP"
"6","(25,3700)","2","mstr_standard","I120";
;
HDL_TAP"TRUE"
BODY_TYPE"PLUMBING"
CDS_LIB"mstr_standard";
"B \NAC \NWC"4;
"S \NAC"
BN"47"118;
%"TAP"
"6","(25,3750)","2","mstr_standard","I121";
;
HDL_TAP"TRUE"
BODY_TYPE"PLUMBING"
CDS_LIB"mstr_standard";
"B \NAC \NWC"4;
"S \NAC"
BN"48"117;
%"TAP"
"6","(25,3950)","2","mstr_standard","I122";
;
HDL_TAP"TRUE"
BODY_TYPE"PLUMBING"
CDS_LIB"mstr_standard";
"B \NAC \NWC"4;
"S \NAC"
BN"52"121;
%"TAP"
"6","(25,3900)","2","mstr_standard","I123";
;
HDL_TAP"TRUE"
BODY_TYPE"PLUMBING"
CDS_LIB"mstr_standard";
"B \NAC \NWC"4;
"S \NAC"
BN"51"122;
%"TAP"
"6","(25,3850)","2","mstr_standard","I124";
;
HDL_TAP"TRUE"
BODY_TYPE"PLUMBING"
CDS_LIB"mstr_standard";
"B \NAC \NWC"4;
"S \NAC"
BN"50"123;
%"TAP"
"6","(25,4000)","2","mstr_standard","I125";
;
HDL_TAP"TRUE"
BODY_TYPE"PLUMBING"
CDS_LIB"mstr_standard";
"B \NAC \NWC"4;
"S \NAC"
BN"53"120;
%"TAP"
"6","(25,4050)","2","mstr_standard","I126";
;
HDL_TAP"TRUE"
BODY_TYPE"PLUMBING"
CDS_LIB"mstr_standard";
"B \NAC \NWC"4;
"S \NAC"
BN"54"119;
%"TAP"
"6","(25,4200)","2","mstr_standard","I127";
;
HDL_TAP"TRUE"
BODY_TYPE"PLUMBING"
CDS_LIB"mstr_standard";
"B \NAC \NWC"4;
"S \NAC"
BN"57"137;
%"TAP"
"6","(25,4150)","2","mstr_standard","I128";
;
HDL_TAP"TRUE"
BODY_TYPE"PLUMBING"
CDS_LIB"mstr_standard";
"B \NAC \NWC"4;
"S \NAC"
BN"56"135;
%"TAP"
"6","(25,4100)","2","mstr_standard","I129";
;
HDL_TAP"TRUE"
BODY_TYPE"PLUMBING"
CDS_LIB"mstr_standard";
"B \NAC \NWC"4;
"S \NAC"
BN"55"136;
%"TAP"
"6","(25,4300)","2","mstr_standard","I130";
;
HDL_TAP"TRUE"
BODY_TYPE"PLUMBING"
CDS_LIB"mstr_standard";
"B \NAC \NWC"4;
"S \NAC"
BN"59"134;
%"TAP"
"6","(25,4250)","2","mstr_standard","I131";
;
HDL_TAP"TRUE"
BODY_TYPE"PLUMBING"
CDS_LIB"mstr_standard";
"B \NAC \NWC"4;
"S \NAC"
BN"58"138;
%"TAP"
"6","(25,4450)","2","mstr_standard","I132";
;
HDL_TAP"TRUE"
BODY_TYPE"PLUMBING"
CDS_LIB"mstr_standard";
"B \NAC \NWC"4;
"S \NAC"
BN"62"140;
%"TAP"
"6","(25,4350)","2","mstr_standard","I133";
;
HDL_TAP"TRUE"
BODY_TYPE"PLUMBING"
CDS_LIB"mstr_standard";
"B \NAC \NWC"4;
"S \NAC"
BN"60"133;
%"TAP"
"6","(25,4400)","2","mstr_standard","I134";
;
HDL_TAP"TRUE"
BODY_TYPE"PLUMBING"
CDS_LIB"mstr_standard";
"B \NAC \NWC"4;
"S \NAC"
BN"61"141;
%"TAP"
"6","(25,4500)","2","mstr_standard","I135";
;
HDL_TAP"TRUE"
BODY_TYPE"PLUMBING"
CDS_LIB"mstr_standard";
"B \NAC \NWC"4;
"S \NAC"
BN"63"139;
%"GND"
"1","(2725,800)","2","mstr_symbols","I137";
;
HDL_POWER"GND"
BODY_TYPE"PLUMBING"
SIZE"1B"
CDS_LIB"mstr_symbols"
VOLTAGE"0";
"A\NAC"14;
%"SCONN288_H44441003"
"3","(3425,2100)","0","mstr_sconn","I138";
;
CDS_SEC"3"
ROOM"DDR4_CH_E"
CDS_LOCATION"J6L2"
SEC"3"
SEC_TYPE"PIP"
CDS_LIB"mstr_sconn"
BOM_COST"MEM"
PACK_TYPE"PIP"
MATERIAL"SCONN"
PART_NUMBER"H44441-003"
LOCATION"J6L2";
"VSS<46>"
$PN"147"15;
"VSS<45>"
$PN"149"15;
"VSS<87>"
$PN"15"14;
"VSS<86>"
$PN"17"14;
"VSS<85>"
$PN"20"14;
"VSS<84>"
$PN"22"14;
"VSS<83>"
$PN"24"14;
"VSS<82>"
$PN"26"14;
"VSS<81>"
$PN"28"14;
"VSS<80>"
$PN"31"14;
"VSS<79>"
$PN"33"14;
"VSS<78>"
$PN"35"14;
"VSS<77>"
$PN"37"14;
"VSS<76>"
$PN"39"14;
"VSS<75>"
$PN"42"14;
"VSS<74>"
$PN"44"14;
"VSS<73>"
$PN"46"14;
"VSS<72>"
$PN"48"14;
"VSS<71>"
$PN"50"14;
"VSS<70>"
$PN"53"14;
"VSS<69>"
$PN"55"14;
"VSS<68>"
$PN"57"14;
"VSS<67>"
$PN"94"14;
"VSS<66>"
$PN"96"14;
"VSS<65>"
$PN"98"14;
"VSS<64>"
$PN"101"14;
"VSS<63>"
$PN"103"14;
"VSS<62>"
$PN"105"14;
"VSS<61>"
$PN"107"14;
"VSS<60>"
$PN"109"14;
"VSS<59>"
$PN"112"14;
"VSS<58>"
$PN"114"14;
"VSS<57>"
$PN"116"14;
"VSS<56>"
$PN"118"14;
"VSS<55>"
$PN"120"14;
"VSS<54>"
$PN"123"14;
"VSS<53>"
$PN"125"14;
"VSS<52>"
$PN"127"14;
"VSS<51>"
$PN"129"14;
"VSS<50>"
$PN"131"14;
"VSS<49>"
$PN"134"14;
"VSS<48>"
$PN"136"14;
"VSS<47>"
$PN"138"14;
"VSS<44>"
$PN"151"15;
"VSS<43>"
$PN"154"15;
"VSS<42>"
$PN"156"15;
"VSS<41>"
$PN"158"15;
"VSS<40>"
$PN"160"15;
"VSS<39>"
$PN"162"15;
"VSS<38>"
$PN"165"15;
"VSS<37>"
$PN"167"15;
"VSS<36>"
$PN"169"15;
"VSS<35>"
$PN"171"15;
"VSS<34>"
$PN"173"15;
"VSS<33>"
$PN"176"15;
"VSS<32>"
$PN"178"15;
"VSS<31>"
$PN"180"15;
"VSS<30>"
$PN"182"15;
"VSS<29>"
$PN"184"15;
"VSS<28>"
$PN"187"15;
"VSS<27>"
$PN"189"15;
"VSS<26>"
$PN"191"15;
"VSS<25>"
$PN"193"15;
"VSS<24>"
$PN"195"15;
"VSS<23>"
$PN"198"15;
"VSS<22>"
$PN"200"15;
"VSS<21>"
$PN"202"15;
"VSS<20>"
$PN"239"15;
"VSS<19>"
$PN"241"15;
"VSS<18>"
$PN"243"15;
"VSS<17>"
$PN"246"15;
"VSS<16>"
$PN"248"15;
"VSS<15>"
$PN"250"15;
"VSS<14>"
$PN"252"15;
"VSS<13>"
$PN"254"15;
"VSS<12>"
$PN"257"15;
"VSS<11>"
$PN"259"15;
"VSS<10>"
$PN"261"15;
"VSS<9>"
$PN"263"15;
"VSS<8>"
$PN"265"15;
"VSS<7>"
$PN"268"15;
"VSS<6>"
$PN"270"15;
"VSS<5>"
$PN"272"15;
"VSS<4>"
$PN"274"15;
"VSS<3>"
$PN"276"15;
"VSS<2>"
$PN"279"15;
"VSS<1>"
$PN"281"15;
"VSS<0>"
$PN"283"15;
"VSS<88>"
$PN"13"14;
"VSS<89>"
$PN"11"14;
"VSS<90>"
$PN"9"14;
"VSS<91>"
$PN"6"14;
"VSS<92>"
$PN"4"14;
"VSS<93>"
$PN"2"14;
%"TAP"
"6","(2325,3050)","2","mstr_standard","I142";
;
HDL_TAP"TRUE"
BODY_TYPE"PLUMBING"
CDS_LIB"mstr_standard";
"B \NAC \NWC"2;
"S \NAC"
BN"0"142;
%"TAP"
"6","(2325,3150)","2","mstr_standard","I143";
;
HDL_TAP"TRUE"
BODY_TYPE"PLUMBING"
CDS_LIB"mstr_standard";
"B \NAC \NWC"2;
"S \NAC"
BN"1"143;
%"TAP"
"6","(2525,3000)","2","mstr_standard","I144";
;
HDL_TAP"TRUE"
BODY_TYPE"PLUMBING"
CDS_LIB"mstr_standard";
"B \NAC \NWC"1;
"S \NAC"
BN"0"23;
%"TAP"
"6","(2525,3100)","2","mstr_standard","I145";
;
HDL_TAP"TRUE"
BODY_TYPE"PLUMBING"
CDS_LIB"mstr_standard";
"B \NAC \NWC"1;
"S \NAC"
BN"1"148;
%"TAP"
"6","(2325,3250)","2","mstr_standard","I146";
;
HDL_TAP"TRUE"
BODY_TYPE"PLUMBING"
CDS_LIB"mstr_standard";
"B \NAC \NWC"2;
"S \NAC"
BN"2"144;
%"TAP"
"6","(2325,3350)","2","mstr_standard","I147";
;
HDL_TAP"TRUE"
BODY_TYPE"PLUMBING"
CDS_LIB"mstr_standard";
"B \NAC \NWC"2;
"S \NAC"
BN"3"145;
%"TAP"
"6","(2325,3450)","2","mstr_standard","I148";
;
HDL_TAP"TRUE"
BODY_TYPE"PLUMBING"
CDS_LIB"mstr_standard";
"B \NAC \NWC"2;
"S \NAC"
BN"4"146;
%"TAP"
"6","(2325,3550)","2","mstr_standard","I149";
;
HDL_TAP"TRUE"
BODY_TYPE"PLUMBING"
CDS_LIB"mstr_standard";
"B \NAC \NWC"2;
"S \NAC"
BN"5"147;
%"TAP"
"6","(2325,3650)","2","mstr_standard","I150";
;
HDL_TAP"TRUE"
BODY_TYPE"PLUMBING"
CDS_LIB"mstr_standard";
"B \NAC \NWC"2;
"S \NAC"
BN"6"153;
%"TAP"
"6","(2525,3400)","2","mstr_standard","I151";
;
HDL_TAP"TRUE"
BODY_TYPE"PLUMBING"
CDS_LIB"mstr_standard";
"B \NAC \NWC"1;
"S \NAC"
BN"4"151;
%"TAP"
"6","(2525,3200)","2","mstr_standard","I152";
;
HDL_TAP"TRUE"
BODY_TYPE"PLUMBING"
CDS_LIB"mstr_standard";
"B \NAC \NWC"1;
"S \NAC"
BN"2"149;
%"TAP"
"6","(2525,3300)","2","mstr_standard","I153";
;
HDL_TAP"TRUE"
BODY_TYPE"PLUMBING"
CDS_LIB"mstr_standard";
"B \NAC \NWC"1;
"S \NAC"
BN"3"150;
%"TAP"
"6","(2525,3600)","2","mstr_standard","I154";
;
HDL_TAP"TRUE"
BODY_TYPE"PLUMBING"
CDS_LIB"mstr_standard";
"B \NAC \NWC"1;
"S \NAC"
BN"6"159;
%"TAP"
"6","(2525,3500)","2","mstr_standard","I155";
;
HDL_TAP"TRUE"
BODY_TYPE"PLUMBING"
CDS_LIB"mstr_standard";
"B \NAC \NWC"1;
"S \NAC"
BN"5"152;
%"GND"
"1","(4125,800)","2","mstr_symbols","I156";
;
HDL_POWER"GND"
BODY_TYPE"PLUMBING"
SIZE"1B"
CDS_LIB"mstr_symbols"
VOLTAGE"0";
"A\NAC"15;
%"TAP"
"6","(2325,3750)","2","mstr_standard","I157";
;
HDL_TAP"TRUE"
BODY_TYPE"PLUMBING"
CDS_LIB"mstr_standard";
"B \NAC \NWC"2;
"S \NAC"
BN"7"154;
%"TAP"
"6","(2325,3950)","2","mstr_standard","I158";
;
HDL_TAP"TRUE"
BODY_TYPE"PLUMBING"
CDS_LIB"mstr_standard";
"B \NAC \NWC"2;
"S \NAC"
BN"9"157;
%"TAP"
"6","(2325,3850)","2","mstr_standard","I159";
;
HDL_TAP"TRUE"
BODY_TYPE"PLUMBING"
CDS_LIB"mstr_standard";
"B \NAC \NWC"2;
"S \NAC"
BN"8"156;
%"TAP"
"6","(2325,4050)","2","mstr_standard","I160";
;
HDL_TAP"TRUE"
BODY_TYPE"PLUMBING"
CDS_LIB"mstr_standard";
"B \NAC \NWC"2;
"S \NAC"
BN"10"155;
%"TAP"
"6","(2325,4150)","2","mstr_standard","I161";
;
HDL_TAP"TRUE"
BODY_TYPE"PLUMBING"
CDS_LIB"mstr_standard";
"B \NAC \NWC"2;
"S \NAC"
BN"11"163;
%"TAP"
"6","(2525,3900)","2","mstr_standard","I162";
;
HDL_TAP"TRUE"
BODY_TYPE"PLUMBING"
CDS_LIB"mstr_standard";
"B \NAC \NWC"1;
"S \NAC"
BN"9"162;
%"TAP"
"6","(2525,3700)","2","mstr_standard","I163";
;
HDL_TAP"TRUE"
BODY_TYPE"PLUMBING"
CDS_LIB"mstr_standard";
"B \NAC \NWC"1;
"S \NAC"
BN"7"160;
%"TAP"
"6","(2525,3800)","2","mstr_standard","I164";
;
HDL_TAP"TRUE"
BODY_TYPE"PLUMBING"
CDS_LIB"mstr_standard";
"B \NAC \NWC"1;
"S \NAC"
BN"8"161;
%"TAP"
"6","(2525,4100)","2","mstr_standard","I165";
;
HDL_TAP"TRUE"
BODY_TYPE"PLUMBING"
CDS_LIB"mstr_standard";
"B \NAC \NWC"1;
"S \NAC"
BN"11"168;
%"TAP"
"6","(2525,4000)","2","mstr_standard","I166";
;
HDL_TAP"TRUE"
BODY_TYPE"PLUMBING"
CDS_LIB"mstr_standard";
"B \NAC \NWC"1;
"S \NAC"
BN"10"158;
%"TAP"
"6","(2525,4200)","2","mstr_standard","I167";
;
HDL_TAP"TRUE"
BODY_TYPE"PLUMBING"
CDS_LIB"mstr_standard";
"B \NAC \NWC"1;
"S \NAC"
BN"12"169;
%"TAP"
"6","(2325,4250)","2","mstr_standard","I168";
;
HDL_TAP"TRUE"
BODY_TYPE"PLUMBING"
CDS_LIB"mstr_standard";
"B \NAC \NWC"2;
"S \NAC"
BN"12"164;
%"TAP"
"6","(2325,4450)","2","mstr_standard","I169";
;
HDL_TAP"TRUE"
BODY_TYPE"PLUMBING"
CDS_LIB"mstr_standard";
"B \NAC \NWC"2;
"S \NAC"
BN"14"166;
%"TAP"
"6","(2325,4350)","2","mstr_standard","I170";
;
HDL_TAP"TRUE"
BODY_TYPE"PLUMBING"
CDS_LIB"mstr_standard";
"B \NAC \NWC"2;
"S \NAC"
BN"13"165;
%"TAP"
"6","(2325,4550)","2","mstr_standard","I171";
;
HDL_TAP"TRUE"
BODY_TYPE"PLUMBING"
CDS_LIB"mstr_standard";
"B \NAC \NWC"2;
"S \NAC"
BN"15"167;
%"TAP"
"6","(2325,4650)","2","mstr_standard","I172";
;
HDL_TAP"TRUE"
BODY_TYPE"PLUMBING"
CDS_LIB"mstr_standard";
"B \NAC \NWC"2;
"S \NAC"
BN"16"174;
%"TAP"
"6","(2525,4400)","2","mstr_standard","I173";
;
HDL_TAP"TRUE"
BODY_TYPE"PLUMBING"
CDS_LIB"mstr_standard";
"B \NAC \NWC"1;
"S \NAC"
BN"14"171;
%"TAP"
"6","(2525,4300)","2","mstr_standard","I174";
;
HDL_TAP"TRUE"
BODY_TYPE"PLUMBING"
CDS_LIB"mstr_standard";
"B \NAC \NWC"1;
"S \NAC"
BN"13"170;
%"TAP"
"6","(2525,4700)","2","mstr_standard","I175";
;
HDL_TAP"TRUE"
BODY_TYPE"PLUMBING"
CDS_LIB"mstr_standard";
"B \NAC \NWC"1;
"S \NAC"
BN"17"176;
%"TAP"
"6","(2525,4600)","2","mstr_standard","I176";
;
HDL_TAP"TRUE"
BODY_TYPE"PLUMBING"
CDS_LIB"mstr_standard";
"B \NAC \NWC"1;
"S \NAC"
BN"16"173;
%"TAP"
"6","(2525,4500)","2","mstr_standard","I177";
;
HDL_TAP"TRUE"
BODY_TYPE"PLUMBING"
CDS_LIB"mstr_standard";
"B \NAC \NWC"1;
"S \NAC"
BN"15"172;
%"TAP"
"6","(2325,4750)","2","mstr_standard","I178";
;
HDL_TAP"TRUE"
BODY_TYPE"PLUMBING"
CDS_LIB"mstr_standard";
"B \NAC \NWC"2;
"S \NAC"
BN"17"175;
%"P12V_NVDIMM_DEF"
"1","(2175,2725)","0","mstr_symbols","I181";
;
HDL_POWER"P12V_NVDIMM_DEF"
BODY_TYPE"PLUMBING"
CDS_LIB"mstr_symbols"
VOLTAGE"12.0";
"G\NAC"16;
%"TAP"
"6","(-1475,2100)","0","mstr_standard","I19";
;
HDL_TAP"TRUE"
BODY_TYPE"PLUMBING"
CDS_LIB"mstr_standard";
"B \NAC \NWC"12;
"S \NAC"
BN"0"55;
%"GND"
"1","(-3025,900)","2","mstr_symbols","I2";
;
HDL_POWER"GND"
BODY_TYPE"PLUMBING"
CDS_LIB"mstr_symbols"
SIZE"1B"
VOLTAGE"0";
"A\NAC"17;
%"TAP"
"6","(-1475,2150)","0","mstr_standard","I20";
;
HDL_TAP"TRUE"
BODY_TYPE"PLUMBING"
CDS_LIB"mstr_standard";
"B \NAC \NWC"12;
"S \NAC"
BN"1"54;
%"TAP"
"6","(-1475,2250)","0","mstr_standard","I21";
;
HDL_TAP"TRUE"
BODY_TYPE"PLUMBING"
CDS_LIB"mstr_standard";
"B \NAC \NWC"12;
"S \NAC"
BN"3"52;
%"TAP"
"6","(-1475,2200)","0","mstr_standard","I22";
;
HDL_TAP"TRUE"
BODY_TYPE"PLUMBING"
CDS_LIB"mstr_standard";
"B \NAC \NWC"12;
"S \NAC"
BN"2"53;
%"TAP"
"6","(-1475,2350)","0","mstr_standard","I23";
;
HDL_TAP"TRUE"
BODY_TYPE"PLUMBING"
CDS_LIB"mstr_standard";
"B \NAC \NWC"12;
"S \NAC"
BN"5"50;
%"TAP"
"6","(-1475,2300)","0","mstr_standard","I24";
;
HDL_TAP"TRUE"
BODY_TYPE"PLUMBING"
CDS_LIB"mstr_standard";
"B \NAC \NWC"12;
"S \NAC"
BN"4"51;
%"TAP"
"6","(-1475,2400)","0","mstr_standard","I25";
;
HDL_TAP"TRUE"
BODY_TYPE"PLUMBING"
CDS_LIB"mstr_standard";
"B \NAC \NWC"12;
"S \NAC"
BN"6"49;
%"TAP"
"6","(-1475,2450)","0","mstr_standard","I26";
;
HDL_TAP"TRUE"
BODY_TYPE"PLUMBING"
CDS_LIB"mstr_standard";
"B \NAC \NWC"12;
"S \NAC"
BN"7"56;
%"TAP"
"6","(-1475,2600)","0","mstr_standard","I27";
;
HDL_TAP"TRUE"
BODY_TYPE"PLUMBING"
CDS_LIB"mstr_standard";
"B \NAC \NWC"11;
"S \NAC"
BN"3"62;
%"TAP"
"6","(-1475,2550)","0","mstr_standard","I28";
;
HDL_TAP"TRUE"
BODY_TYPE"PLUMBING"
CDS_LIB"mstr_standard";
"B \NAC \NWC"11;
"S \NAC"
BN"2"57;
%"CAP_A"
"1","(-3025,1150)","2","dev_discrete","I3";
;
ROOM"DDR4_CH_E"
$SEC"1"
CDS_SEC"1"
CDS_LIB"dev_discrete"
BOM_COST"MEM"
CDS_LOCATION"C4A18"
MATERIAL"X7R"
VOLTAGE"25V"
PACK_TYPE"0402V"
TOLERANCE"10%"
VALUE"0.01UF"
PART_NUMBER"A36096-045"
LOCATION"C4A18";
"B"
$PN"2"17;
"A"
$PN"1"22;
%"TAP"
"6","(-2025,3150)","0","mstr_standard","I32";
;
HDL_TAP"TRUE"
BODY_TYPE"PLUMBING"
CDS_LIB"mstr_standard";
"B \NAC \NWC"7;
"S \NAC"
BN"2"69;
%"TAP"
"6","(-2025,3250)","0","mstr_standard","I35";
;
HDL_TAP"TRUE"
BODY_TYPE"PLUMBING"
CDS_LIB"mstr_standard";
"B \NAC \NWC"7;
"S \NAC"
BN"3"68;
%"TAP"
"6","(-1525,2750)","0","mstr_standard","I36";
;
HDL_TAP"TRUE"
BODY_TYPE"PLUMBING"
CDS_LIB"mstr_standard";
"B \NAC \NWC"10;
"S \NAC"
BN"3"61;
%"TAP"
"6","(-1525,2700)","0","mstr_standard","I37";
;
HDL_TAP"TRUE"
BODY_TYPE"PLUMBING"
CDS_LIB"mstr_standard";
"B \NAC \NWC"10;
"S \NAC"
BN"2"63;
%"TAP"
"6","(-1475,2900)","0","mstr_standard","I38";
;
HDL_TAP"TRUE"
BODY_TYPE"PLUMBING"
CDS_LIB"mstr_standard";
"B \NAC \NWC"9;
"S \NAC"
BN"5"60;
%"TAP"
"6","(-1475,2850)","0","mstr_standard","I39";
;
HDL_TAP"TRUE"
BODY_TYPE"PLUMBING"
CDS_LIB"mstr_standard";
"B \NAC \NWC"9;
"S \NAC"
BN"4"64;
%"TAP"
"6","(-1475,3000)","0","mstr_standard","I40";
;
HDL_TAP"TRUE"
BODY_TYPE"PLUMBING"
CDS_LIB"mstr_standard";
"B \NAC \NWC"9;
"S \NAC"
BN"7"58;
%"TAP"
"6","(-1475,2950)","0","mstr_standard","I41";
;
HDL_TAP"TRUE"
BODY_TYPE"PLUMBING"
CDS_LIB"mstr_standard";
"B \NAC \NWC"9;
"S \NAC"
BN"6"59;
%"TAP"
"6","(-1875,3300)","0","mstr_standard","I42";
;
HDL_TAP"TRUE"
BODY_TYPE"PLUMBING"
CDS_LIB"mstr_standard";
"B \NAC \NWC"8;
"S \NAC"
BN"3"67;
%"TAP"
"6","(-1875,3200)","0","mstr_standard","I43";
;
HDL_TAP"TRUE"
BODY_TYPE"PLUMBING"
CDS_LIB"mstr_standard";
"B \NAC \NWC"8;
"S \NAC"
BN"2"66;
%"TAP"
"6","(-1475,3400)","0","mstr_standard","I44";
;
HDL_TAP"TRUE"
BODY_TYPE"PLUMBING"
CDS_LIB"mstr_standard";
"B \NAC \NWC"6;
"S \NAC"
BN"0"71;
%"TAP"
"6","(-1475,3450)","0","mstr_standard","I45";
;
HDL_TAP"TRUE"
BODY_TYPE"PLUMBING"
CDS_LIB"mstr_standard";
"B \NAC \NWC"6;
"S \NAC"
BN"1"72;
%"TAP"
"6","(-1475,3500)","0","mstr_standard","I46";
;
HDL_TAP"TRUE"
BODY_TYPE"PLUMBING"
CDS_LIB"mstr_standard";
"B \NAC \NWC"5;
"S \NAC"
BN"0"73;
%"TAP"
"6","(-1475,3550)","0","mstr_standard","I47";
;
HDL_TAP"TRUE"
BODY_TYPE"PLUMBING"
CDS_LIB"mstr_standard";
"B \NAC \NWC"5;
"S \NAC"
BN"1"70;
%"TAP"
"6","(-1475,3650)","0","mstr_standard","I48";
;
HDL_TAP"TRUE"
BODY_TYPE"PLUMBING"
CDS_LIB"mstr_standard";
"B \NAC \NWC"3;
"S \NAC"
BN"0"74;
%"TAP"
"6","(25,1350)","2","mstr_standard","I49";
;
HDL_TAP"TRUE"
BODY_TYPE"PLUMBING"
CDS_LIB"mstr_standard";
"B \NAC \NWC"4;
"S \NAC"
BN"0"33;
%"PVPP_DEF"
"1","(-3575,1850)","0","mstr_symbols","I5";
;
HDL_POWER"PVPP_DEF"
BODY_TYPE"PLUMBING"
CDS_LIB"mstr_symbols"
VOLTAGE"2.5V";
"G\NAC"18;
%"TAP"
"6","(25,1500)","2","mstr_standard","I50";
;
HDL_TAP"TRUE"
BODY_TYPE"PLUMBING"
CDS_LIB"mstr_standard";
"B \NAC \NWC"4;
"S \NAC"
BN"3"35;
%"TAP"
"6","(25,1400)","2","mstr_standard","I51";
;
HDL_TAP"TRUE"
BODY_TYPE"PLUMBING"
CDS_LIB"mstr_standard";
"B \NAC \NWC"4;
"S \NAC"
BN"1"32;
%"TAP"
"6","(25,1450)","2","mstr_standard","I52";
;
HDL_TAP"TRUE"
BODY_TYPE"PLUMBING"
CDS_LIB"mstr_standard";
"B \NAC \NWC"4;
"S \NAC"
BN"2"34;
%"TAP"
"6","(25,1600)","2","mstr_standard","I53";
;
HDL_TAP"TRUE"
BODY_TYPE"PLUMBING"
CDS_LIB"mstr_standard";
"B \NAC \NWC"4;
"S \NAC"
BN"5"40;
%"TAP"
"6","(25,1550)","2","mstr_standard","I54";
;
HDL_TAP"TRUE"
BODY_TYPE"PLUMBING"
CDS_LIB"mstr_standard";
"B \NAC \NWC"4;
"S \NAC"
BN"4"39;
%"SCONN288_H44441003"
"4","(1475,1650)","0","mstr_sconn","I55";
;
CDS_SEC"4"
ROOM"DDR4_CH_E"
CDS_LOCATION"J6L2"
SEC"4"
SEC_TYPE"PIP"
CDS_LIB"mstr_sconn"
BOM_COST"MEM"
PACK_TYPE"PIP"
MATERIAL"SCONN"
PART_NUMBER"H44441-003"
LOCATION"J6L2";
"VDD<0>"
$PN"236"19;
"VDD<6>"
$PN"220"19;
"VDD<10>"
$PN"209"19;
"VDD<13>"
$PN"92"19;
"VDD<16>"
$PN"85"19;
"VDD<19>"
$PN"76"19;
"VDD<23>"
$PN"64"19;
"VDD<25>"
$PN"59"19;
"VTT<0>"
$PN"221"20;
"12V<1>"
$PN"1"16;
"12V<0>"
$PN"145"16;
"VDD<24>"
$PN"61"19;
"VDD<22>"
$PN"67"19;
"VDD<21>"
$PN"70"19;
"VDD<20>"
$PN"73"19;
"VDD<18>"
$PN"80"19;
"VDD<17>"
$PN"83"19;
"VDD<15>"
$PN"88"19;
"VDD<14>"
$PN"90"19;
"VDD<12>"
$PN"204"19;
"VDD<11>"
$PN"206"19;
"VDD<9>"
$PN"212"19;
"VDD<8>"
$PN"215"19;
"VDD<7>"
$PN"217"19;
"VDD<5>"
$PN"223"19;
"VDD<4>"
$PN"226"19;
"VDD<3>"
$PN"229"19;
"VDD<2>"
$PN"231"19;
"VDD<1>"
$PN"233"19;
"VPP<4>"
$PN"142"21;
"VPP<3>"
$PN"143"21;
"VPP<2>"
$PN"288"21;
"VPP<1>"
$PN"286"21;
"VPP<0>"
$PN"287"21;
"VTT<1>"
$PN"77"20;
%"TAP"
"6","(25,1700)","2","mstr_standard","I56";
;
HDL_TAP"TRUE"
BODY_TYPE"PLUMBING"
CDS_LIB"mstr_standard";
"B \NAC \NWC"4;
"S \NAC"
BN"7"37;
%"TAP"
"6","(25,1750)","2","mstr_standard","I57";
;
HDL_TAP"TRUE"
BODY_TYPE"PLUMBING"
CDS_LIB"mstr_standard";
"B \NAC \NWC"4;
"S \NAC"
BN"8"36;
%"TAP"
"6","(25,1650)","2","mstr_standard","I58";
;
HDL_TAP"TRUE"
BODY_TYPE"PLUMBING"
CDS_LIB"mstr_standard";
"B \NAC \NWC"4;
"S \NAC"
BN"6"38;
%"TAP"
"6","(25,1850)","2","mstr_standard","I59";
;
HDL_TAP"TRUE"
BODY_TYPE"PLUMBING"
CDS_LIB"mstr_standard";
"B \NAC \NWC"4;
"S \NAC"
BN"10"44;
%"TAP"
"6","(25,1800)","2","mstr_standard","I60";
;
HDL_TAP"TRUE"
BODY_TYPE"PLUMBING"
CDS_LIB"mstr_standard";
"B \NAC \NWC"4;
"S \NAC"
BN"9"45;
%"TAP"
"6","(25,1900)","2","mstr_standard","I61";
;
HDL_TAP"TRUE"
BODY_TYPE"PLUMBING"
CDS_LIB"mstr_standard";
"B \NAC \NWC"4;
"S \NAC"
BN"11"43;
%"TAP"
"6","(25,1950)","2","mstr_standard","I62";
;
HDL_TAP"TRUE"
BODY_TYPE"PLUMBING"
CDS_LIB"mstr_standard";
"B \NAC \NWC"4;
"S \NAC"
BN"12"42;
%"TAP"
"6","(25,2000)","2","mstr_standard","I63";
;
HDL_TAP"TRUE"
BODY_TYPE"PLUMBING"
CDS_LIB"mstr_standard";
"B \NAC \NWC"4;
"S \NAC"
BN"13"41;
%"TAP"
"6","(25,2150)","2","mstr_standard","I64";
;
HDL_TAP"TRUE"
BODY_TYPE"PLUMBING"
CDS_LIB"mstr_standard";
"B \NAC \NWC"4;
"S \NAC"
BN"16"85;
%"TAP"
"6","(25,2100)","2","mstr_standard","I65";
;
HDL_TAP"TRUE"
BODY_TYPE"PLUMBING"
CDS_LIB"mstr_standard";
"B \NAC \NWC"4;
"S \NAC"
BN"15"87;
%"TAP"
"6","(25,2050)","2","mstr_standard","I66";
;
HDL_TAP"TRUE"
BODY_TYPE"PLUMBING"
CDS_LIB"mstr_standard";
"B \NAC \NWC"4;
"S \NAC"
BN"14"86;
%"TAP"
"6","(25,2250)","2","mstr_standard","I67";
;
HDL_TAP"TRUE"
BODY_TYPE"PLUMBING"
CDS_LIB"mstr_standard";
"B \NAC \NWC"4;
"S \NAC"
BN"18"84;
%"TAP"
"6","(25,2200)","2","mstr_standard","I68";
;
HDL_TAP"TRUE"
BODY_TYPE"PLUMBING"
CDS_LIB"mstr_standard";
"B \NAC \NWC"4;
"S \NAC"
BN"17"88;
%"TAP"
"6","(25,2400)","2","mstr_standard","I69";
;
HDL_TAP"TRUE"
BODY_TYPE"PLUMBING"
CDS_LIB"mstr_standard";
"B \NAC \NWC"4;
"S \NAC"
BN"21"92;
%"TAP"
"6","(25,2350)","2","mstr_standard","I70";
;
HDL_TAP"TRUE"
BODY_TYPE"PLUMBING"
CDS_LIB"mstr_standard";
"B \NAC \NWC"4;
"S \NAC"
BN"20"93;
%"TAP"
"6","(25,2300)","2","mstr_standard","I71";
;
HDL_TAP"TRUE"
BODY_TYPE"PLUMBING"
CDS_LIB"mstr_standard";
"B \NAC \NWC"4;
"S \NAC"
BN"19"83;
%"TAP"
"6","(25,2450)","2","mstr_standard","I72";
;
HDL_TAP"TRUE"
BODY_TYPE"PLUMBING"
CDS_LIB"mstr_standard";
"B \NAC \NWC"4;
"S \NAC"
BN"22"91;
%"TAP"
"6","(25,2500)","2","mstr_standard","I73";
;
HDL_TAP"TRUE"
BODY_TYPE"PLUMBING"
CDS_LIB"mstr_standard";
"B \NAC \NWC"4;
"S \NAC"
BN"23"90;
%"TAP"
"6","(25,2650)","2","mstr_standard","I74";
;
HDL_TAP"TRUE"
BODY_TYPE"PLUMBING"
CDS_LIB"mstr_standard";
"B \NAC \NWC"4;
"S \NAC"
BN"26"98;
%"TAP"
"6","(25,2550)","2","mstr_standard","I75";
;
HDL_TAP"TRUE"
BODY_TYPE"PLUMBING"
CDS_LIB"mstr_standard";
"B \NAC \NWC"4;
"S \NAC"
BN"24"89;
%"TAP"
"6","(25,2600)","2","mstr_standard","I76";
;
HDL_TAP"TRUE"
BODY_TYPE"PLUMBING"
CDS_LIB"mstr_standard";
"B \NAC \NWC"4;
"S \NAC"
BN"25"96;
%"PVDDQ_DEF"
"1","(375,2200)","0","mstr_symbols","I77";
;
HDL_POWER"PVDDQ_DEF"
BODY_TYPE"PLUMBING"
CDS_LIB"mstr_symbols"
VOLTAGE"1.2V";
"G\NAC"19;
%"TAP"
"6","(25,2700)","2","mstr_standard","I78";
;
HDL_TAP"TRUE"
BODY_TYPE"PLUMBING"
CDS_LIB"mstr_standard";
"B \NAC \NWC"4;
"S \NAC"
BN"27"97;
%"TAP"
"6","(25,2750)","2","mstr_standard","I79";
;
HDL_TAP"TRUE"
BODY_TYPE"PLUMBING"
CDS_LIB"mstr_standard";
"B \NAC \NWC"4;
"S \NAC"
BN"28"95;
%"TAP"
"6","(25,2800)","2","mstr_standard","I80";
;
HDL_TAP"TRUE"
BODY_TYPE"PLUMBING"
CDS_LIB"mstr_standard";
"B \NAC \NWC"4;
"S \NAC"
BN"29"94;
%"TAP"
"6","(25,2900)","2","mstr_standard","I81";
;
HDL_TAP"TRUE"
BODY_TYPE"PLUMBING"
CDS_LIB"mstr_standard";
"B \NAC \NWC"4;
"S \NAC"
BN"31"102;
%"TAP"
"6","(25,2850)","2","mstr_standard","I82";
;
HDL_TAP"TRUE"
BODY_TYPE"PLUMBING"
CDS_LIB"mstr_standard";
"B \NAC \NWC"4;
"S \NAC"
BN"30"103;
%"TAP"
"6","(25,3050)","2","mstr_standard","I83";
;
HDL_TAP"TRUE"
BODY_TYPE"PLUMBING"
CDS_LIB"mstr_standard";
"B \NAC \NWC"4;
"S \NAC"
BN"34"99;
%"TAP"
"6","(25,3000)","2","mstr_standard","I84";
;
HDL_TAP"TRUE"
BODY_TYPE"PLUMBING"
CDS_LIB"mstr_standard";
"B \NAC \NWC"4;
"S \NAC"
BN"33"100;
%"TAP"
"6","(25,2950)","2","mstr_standard","I85";
;
HDL_TAP"TRUE"
BODY_TYPE"PLUMBING"
CDS_LIB"mstr_standard";
"B \NAC \NWC"4;
"S \NAC"
BN"32"101;
%"TAP"
"6","(25,3150)","2","mstr_standard","I86";
;
HDL_TAP"TRUE"
BODY_TYPE"PLUMBING"
CDS_LIB"mstr_standard";
"B \NAC \NWC"4;
"S \NAC"
BN"36"107;
%"TAP"
"6","(25,3100)","2","mstr_standard","I87";
;
HDL_TAP"TRUE"
BODY_TYPE"PLUMBING"
CDS_LIB"mstr_standard";
"B \NAC \NWC"4;
"S \NAC"
BN"35"106;
%"TAP"
"6","(25,3300)","2","mstr_standard","I88";
;
HDL_TAP"TRUE"
BODY_TYPE"PLUMBING"
CDS_LIB"mstr_standard";
"B \NAC \NWC"4;
"S \NAC"
BN"39"104;
%"TAP"
"6","(25,3250)","2","mstr_standard","I89";
;
HDL_TAP"TRUE"
BODY_TYPE"PLUMBING"
CDS_LIB"mstr_standard";
"B \NAC \NWC"4;
"S \NAC"
BN"38"108;
%"TAP"
"6","(25,3200)","2","mstr_standard","I90";
;
HDL_TAP"TRUE"
BODY_TYPE"PLUMBING"
CDS_LIB"mstr_standard";
"B \NAC \NWC"4;
"S \NAC"
BN"37"105;
%"TAP"
"6","(25,3350)","2","mstr_standard","I91";
;
HDL_TAP"TRUE"
BODY_TYPE"PLUMBING"
CDS_LIB"mstr_standard";
"B \NAC \NWC"4;
"S \NAC"
BN"40"113;
%"TAP"
"6","(25,3400)","2","mstr_standard","I92";
;
HDL_TAP"TRUE"
BODY_TYPE"PLUMBING"
CDS_LIB"mstr_standard";
"B \NAC \NWC"4;
"S \NAC"
BN"41"112;
%"TAP"
"6","(25,3550)","2","mstr_standard","I93";
;
HDL_TAP"TRUE"
BODY_TYPE"PLUMBING"
CDS_LIB"mstr_standard";
"B \NAC \NWC"4;
"S \NAC"
BN"44"109;
%"TAP"
"6","(25,3500)","2","mstr_standard","I94";
;
HDL_TAP"TRUE"
BODY_TYPE"PLUMBING"
CDS_LIB"mstr_standard";
"B \NAC \NWC"4;
"S \NAC"
BN"43"110;
%"TAP"
"6","(25,3450)","2","mstr_standard","I95";
;
HDL_TAP"TRUE"
BODY_TYPE"PLUMBING"
CDS_LIB"mstr_standard";
"B \NAC \NWC"4;
"S \NAC"
BN"42"111;
%"TAP"
"6","(25,3650)","2","mstr_standard","I96";
;
HDL_TAP"TRUE"
BODY_TYPE"PLUMBING"
CDS_LIB"mstr_standard";
"B \NAC \NWC"4;
"S \NAC"
BN"46"114;
%"TAP"
"6","(25,3600)","2","mstr_standard","I97";
;
HDL_TAP"TRUE"
BODY_TYPE"PLUMBING"
CDS_LIB"mstr_standard";
"B \NAC \NWC"4;
"S \NAC"
BN"45"115;
%"PVTT_DEF"
"1","(625,2350)","0","mstr_symbols","I98";
;
HDL_POWER"PVTT_DEF"
BODY_TYPE"PLUMBING"
CDS_LIB"mstr_symbols"
VOLTAGE"0.6V";
"G\NAC"20;
%"PVPP_DEF"
"1","(775,2650)","0","mstr_symbols","I99";
;
HDL_POWER"PVPP_DEF"
BODY_TYPE"PLUMBING"
CDS_LIB"mstr_symbols"
VOLTAGE"2.5V";
"G\NAC"21;
END.
